# T6G (Grand Teton) — schematic netlist excerpt (pin names and nets, part order shuffled) for the footprints in the layout excerpt that follows; sources: Cadence DE-HDL packaged netlist, KiCad conversion of 04192023_DAF0TMB3IC0_F0TG_MB_C_brd_V02_OCP.brd

R3764  Q_RES  4.7K 1% EMPTY  pkg 0402LF  page 236 : A = GND ; B = INA230_2_A0
PC169_1  Q_CAP  22UF 4V 20% X6S  pkg C0805  page 205 : A = PVDDIO_P0 ; B = GND
PR444  Q_RES  1K 1% CHIP  pkg 0402LF  page 201 : A = PVDDCR_CPU1_P0 ; B = GND

(kicad_pcb
	(version 20260206)
	(generator "pcbnew")
	(generator_version "10.0")
	(general
		(thickness 1.6)
		(legacy_teardrops no)
	)
	(paper "A4")
	(title_block
		(title "04192023_DAF0TMB3IC0_F0TG_MB_C_brd_V02_OCP.brd")
		(comment 1 "Grand Teton / footprints 8008-8010 of 8354")
	)
	(layers
		(0 "F.Cu" signal "TOP")
		(4 "In1.Cu" signal "GND")
		(6 "In2.Cu" signal "IN1")
		(8 "In3.Cu" signal "GND1")
		(10 "In4.Cu" signal "IN2")
		(12 "In5.Cu" signal "GND2")
		(14 "In6.Cu" signal "IN3")
		(16 "In7.Cu" signal "GND3")
		(18 "In8.Cu" signal "VCC")
		(20 "In9.Cu" signal "VCC1")
		(22 "In10.Cu" signal "GND4")
		(24 "In11.Cu" signal "IN4")
		(26 "In12.Cu" signal "GND5")
		(28 "In13.Cu" signal "IN5")
		(30 "In14.Cu" signal "GND6")
		(32 "In15.Cu" signal "IN6")
		(34 "In16.Cu" signal "GND7")
		(2 "B.Cu" signal "BOTTOM")
		(9 "F.Adhes" user "F.Adhesive")
		(11 "B.Adhes" user "B.Adhesive")
		(13 "F.Paste" user "Package Geometry/Pastemask Top")
		(15 "B.Paste" user "Package Geometry/Pastemask Bottom")
		(5 "F.SilkS" user "Ref Des/Silkscreen Top")
		(7 "B.SilkS" user "Ref Des/Silkscreen Bottom")
		(1 "F.Mask" user "Board Geometry/Soldermask Top")
		(3 "B.Mask" user "Board Geometry/Soldermask Bottom")
		(17 "Dwgs.User" user "User.Drawings")
		(19 "Cmts.User" user "User.Comments")
		(21 "Eco1.User" user "User.Eco1")
		(23 "Eco2.User" user "User.Eco2")
		(25 "Edge.Cuts" user "Board Geometry/Outline")
		(27 "Margin" user)
		(31 "F.CrtYd" user "Package Geometry/Place Bound Top")
		(29 "B.CrtYd" user "Package Geometry/Place Bound Bottom")
		(35 "F.Fab" user "Ref Des/Assembly Top")
		(33 "B.Fab" user "Ref Des/Assembly Bottom")
	)
	(footprint ""
		(layer "B.Cu")
		(at 357.044244 -331.408532 -90)
		(property "Reference" "PR444"
			(at 0 0 90)
			(layer "B.SilkS")
			(hide yes)
			(effects
				(font
					(size 1.27 1.27)
				)
				(justify mirror)
			)
		)
		(property "Value" ""
			(at 0 0 90)
			(layer "B.Fab")
			(effects
				(font
					(size 1.27 1.27)
				)
				(justify mirror)
			)
		)
		(duplicate_pad_numbers_are_jumpers no)
		(fp_line
			(start -0.7874 0.4064)
			(end 0.7874 0.4064)
			(stroke
				(width 0.1524)
				(type default)
			)
			(layer "B.SilkS")
		)
		(fp_line
			(start 0.7874 0.4064)
			(end 0.7874 -0.4064)
			(stroke
				(width 0.1524)
				(type default)
			)
			(layer "B.SilkS")
		)
		(fp_line
			(start -0.7874 -0.4064)
			(end -0.7874 0.4064)
			(stroke
				(width 0.1524)
				(type default)
			)
			(layer "B.SilkS")
		)
		(fp_line
			(start 0.7874 -0.4064)
			(end -0.7874 -0.4064)
			(stroke
				(width 0.1524)
				(type default)
			)
			(layer "B.SilkS")
		)
		(fp_line
			(start -0.67945 0.3048)
			(end -0.120396 0.3048)
			(stroke
				(width 0.1)
				(type default)
			)
			(layer "B.Fab")
		)
		(fp_line
			(start -0.120396 0.3048)
			(end -0.120396 0.2794)
			(stroke
				(width 0.1)
				(type default)
			)
			(layer "B.Fab")
		)
		(fp_line
			(start 0.12065 0.3048)
			(end 0.67945 0.3048)
			(stroke
				(width 0.1)
				(type default)
			)
			(layer "B.Fab")
		)
		(fp_line
			(start 0.67945 0.3048)
			(end 0.67945 -0.305054)
			(stroke
				(width 0.1)
				(type default)
			)
			(layer "B.Fab")
		)
		(fp_line
			(start -0.120396 0.2794)
			(end 0.12065 0.2794)
			(stroke
				(width 0.1)
				(type default)
			)
			(layer "B.Fab")
		)
		(fp_line
			(start 0.12065 0.2794)
			(end 0.12065 0.3048)
			(stroke
				(width 0.1)
				(type default)
			)
			(layer "B.Fab")
		)
		(fp_line
			(start -0.12065 -0.2794)
			(end -0.12065 -0.3048)
			(stroke
				(width 0.1)
				(type default)
			)
			(layer "B.Fab")
		)
		(fp_line
			(start 0.12065 -0.2794)
			(end -0.12065 -0.2794)
			(stroke
				(width 0.1)
				(type default)
			)
			(layer "B.Fab")
		)
		(fp_line
			(start -0.67945 -0.3048)
			(end -0.67945 0.3048)
			(stroke
				(width 0.1)
				(type default)
			)
			(layer "B.Fab")
		)
		(fp_line
			(start -0.12065 -0.3048)
			(end -0.67945 -0.3048)
			(stroke
				(width 0.1)
				(type default)
			)
			(layer "B.Fab")
		)
		(fp_line
			(start 0.12065 -0.305054)
			(end 0.12065 -0.2794)
			(stroke
				(width 0.1)
				(type default)
			)
			(layer "B.Fab")
		)
		(fp_line
			(start 0.67945 -0.305054)
			(end 0.12065 -0.305054)
			(stroke
				(width 0.1)
				(type default)
			)
			(layer "B.Fab")
		)
		(pad "1" smd circle
			(at 0.40005 0 90)
			(size 0 0)
			(layers "B.Cu" "B.Mask" "B.Paste")
			(net "PVDDCR_CPU1_P0")
		)
		(pad "2" smd circle
			(at -0.40005 0 90)
			(size 0 0)
			(layers "B.Cu" "B.Mask" "B.Paste")
			(net "GND")
		)
	)
	(footprint ""
		(layer "B.Cu")
		(at 214.43188 -55.971948)
		(property "Reference" "R3764"
			(at 0 0 0)
			(layer "B.SilkS")
			(hide yes)
			(effects
				(font
					(size 1.27 1.27)
				)
				(justify mirror)
			)
		)
		(property "Value" ""
			(at 0 0 0)
			(layer "B.Fab")
			(effects
				(font
					(size 1.27 1.27)
				)
				(justify mirror)
			)
		)
		(duplicate_pad_numbers_are_jumpers no)
		(fp_line
			(start -0.7874 -0.4064)
			(end -0.7874 0.4064)
			(stroke
				(width 0.1524)
				(type default)
			)
			(layer "B.SilkS")
		)
		(fp_line
			(start -0.7874 0.4064)
			(end 0.7874 0.4064)
			(stroke
				(width 0.1524)
				(type default)
			)
			(layer "B.SilkS")
		)
		(fp_line
			(start 0.7874 -0.4064)
			(end -0.7874 -0.4064)
			(stroke
				(width 0.1524)
				(type default)
			)
			(layer "B.SilkS")
		)
		(fp_line
			(start 0.7874 0.4064)
			(end 0.7874 -0.4064)
			(stroke
				(width 0.1524)
				(type default)
			)
			(layer "B.SilkS")
		)
		(fp_line
			(start -0.67945 -0.3048)
			(end -0.67945 0.3048)
			(stroke
				(width 0.1)
				(type default)
			)
			(layer "B.Fab")
		)
		(fp_line
			(start -0.67945 0.3048)
			(end -0.120396 0.3048)
			(stroke
				(width 0.1)
				(type default)
			)
			(layer "B.Fab")
		)
		(fp_line
			(start -0.12065 -0.3048)
			(end -0.67945 -0.3048)
			(stroke
				(width 0.1)
				(type default)
			)
			(layer "B.Fab")
		)
		(fp_line
			(start -0.12065 -0.2794)
			(end -0.12065 -0.3048)
			(stroke
				(width 0.1)
				(type default)
			)
			(layer "B.Fab")
		)
		(fp_line
			(start -0.120396 0.2794)
			(end 0.12065 0.2794)
			(stroke
				(width 0.1)
				(type default)
			)
			(layer "B.Fab")
		)
		(fp_line
			(start -0.120396 0.3048)
			(end -0.120396 0.2794)
			(stroke
				(width 0.1)
				(type default)
			)
			(layer "B.Fab")
		)
		(fp_line
			(start 0.12065 -0.305054)
			(end 0.12065 -0.2794)
			(stroke
				(width 0.1)
				(type default)
			)
			(layer "B.Fab")
		)
		(fp_line
			(start 0.12065 -0.2794)
			(end -0.12065 -0.2794)
			(stroke
				(width 0.1)
				(type default)
			)
			(layer "B.Fab")
		)
		(fp_line
			(start 0.12065 0.2794)
			(end 0.12065 0.3048)
			(stroke
				(width 0.1)
				(type default)
			)
			(layer "B.Fab")
		)
		(fp_line
			(start 0.12065 0.3048)
			(end 0.67945 0.3048)
			(stroke
				(width 0.1)
				(type default)
			)
			(layer "B.Fab")
		)
		(fp_line
			(start 0.67945 -0.305054)
			(end 0.12065 -0.305054)
			(stroke
				(width 0.1)
				(type default)
			)
			(layer "B.Fab")
		)
		(fp_line
			(start 0.67945 0.3048)
			(end 0.67945 -0.305054)
			(stroke
				(width 0.1)
				(type default)
			)
			(layer "B.Fab")
		)
		(pad "1" smd circle
			(at 0.40005 0 180)
			(size 0 0)
			(layers "B.Cu" "B.Mask" "B.Paste")
			(net "GND")
		)
		(pad "2" smd circle
			(at -0.40005 0 180)
			(size 0 0)
			(layers "B.Cu" "B.Mask" "B.Paste")
			(net "INA230_2_A0")
		)
	)
	(footprint ""
		(layer "B.Cu")
		(at 293.80688 -337.984846 -90)
		(property "Reference" "PC169_1"
			(at 0 0 90)
			(layer "B.SilkS")
			(hide yes)
			(effects
				(font
					(size 1.27 1.27)
				)
				(justify mirror)
			)
		)
		(property "Value" ""
			(at 0 0 90)
			(layer "B.Fab")
			(effects
				(font
					(size 1.27 1.27)
				)
				(justify mirror)
			)
		)
		(duplicate_pad_numbers_are_jumpers no)
		(fp_line
			(start -1.524 0.762)
			(end 1.524 0.762)
			(stroke
				(width 0.1524)
				(type default)
			)
			(layer "B.SilkS")
		)
		(fp_line
			(start 1.524 0.762)
			(end 1.524 -0.762)
			(stroke
				(width 0.1524)
				(type default)
			)
			(layer "B.SilkS")
		)
		(fp_line
			(start -1.524 -0.762)
			(end -1.524 0.762)
			(stroke
				(width 0.1524)
				(type default)
			)
			(layer "B.SilkS")
		)
		(fp_line
			(start 1.524 -0.762)
			(end -1.524 -0.762)
			(stroke
				(width 0.1524)
				(type default)
			)
			(layer "B.SilkS")
		)
		(fp_line
			(start -1.1049 0.724916)
			(end -1.1049 -0.724916)
			(stroke
				(width 0.1)
				(type default)
			)
			(layer "B.Fab")
		)
		(fp_line
			(start 1.1049 0.724916)
			(end -1.1049 0.724916)
			(stroke
				(width 0.1)
				(type default)
			)
			(layer "B.Fab")
		)
		(fp_line
			(start -1.1049 -0.724916)
			(end 1.1049 -0.724916)
			(stroke
				(width 0.1)
				(type default)
			)
			(layer "B.Fab")
		)
		(fp_line
			(start 1.1049 -0.724916)
			(end 1.1049 0.724916)
			(stroke
				(width 0.1)
				(type default)
			)
			(layer "B.Fab")
		)
		(pad "1" smd rect
			(at 0.889 0 270)
			(size 1.016 1.27)
			(layers "B.Cu" "B.Mask" "B.Paste")
			(net "PVDDIO_P0")
		)
		(pad "2" smd rect
			(at -0.889 0 270)
			(size 1.016 1.27)
			(layers "B.Cu" "B.Mask" "B.Paste")
			(net "GND")
		)
	)
)
